# T6G (Grand Teton) — schematic netlist excerpt (pin names and nets, part order shuffled) for the footprints in the layout excerpt that follows; sources: Cadence DE-HDL packaged netlist, KiCad conversion of 04192023_DAF0TMB3IC0_F0TG_MB_C_brd_V02_OCP.brd

R34  Q_RES  4.7K 1% CHIP  pkg 0402LF  page 131 : A = OCP_SFF_ID1 ; B = GND
R3939  Q_RES  0 5% EMPTY  pkg 0402LF  page 257 : A = P12V_E1S_0_ISENSE_MAM_MAM ; B = P12V_E1S_0_ISENSE_MAM

(kicad_pcb
	(version 20260206)
	(generator "pcbnew")
	(generator_version "10.0")
	(general
		(thickness 1.6)
		(legacy_teardrops no)
	)
	(paper "A4")
	(title_block
		(title "04192023_DAF0TMB3IC0_F0TG_MB_C_brd_V02_OCP.brd")
		(comment 1 "Grand Teton / footprints 6449-6450 of 8354")
	)
	(layers
		(0 "F.Cu" signal "TOP")
		(4 "In1.Cu" signal "GND")
		(6 "In2.Cu" signal "IN1")
		(8 "In3.Cu" signal "GND1")
		(10 "In4.Cu" signal "IN2")
		(12 "In5.Cu" signal "GND2")
		(14 "In6.Cu" signal "IN3")
		(16 "In7.Cu" signal "GND3")
		(18 "In8.Cu" signal "VCC")
		(20 "In9.Cu" signal "VCC1")
		(22 "In10.Cu" signal "GND4")
		(24 "In11.Cu" signal "IN4")
		(26 "In12.Cu" signal "GND5")
		(28 "In13.Cu" signal "IN5")
		(30 "In14.Cu" signal "GND6")
		(32 "In15.Cu" signal "IN6")
		(34 "In16.Cu" signal "GND7")
		(2 "B.Cu" signal "BOTTOM")
		(9 "F.Adhes" user "F.Adhesive")
		(11 "B.Adhes" user "B.Adhesive")
		(13 "F.Paste" user "Package Geometry/Pastemask Top")
		(15 "B.Paste" user "Package Geometry/Pastemask Bottom")
		(5 "F.SilkS" user "Ref Des/Silkscreen Top")
		(7 "B.SilkS" user "Ref Des/Silkscreen Bottom")
		(1 "F.Mask" user "Board Geometry/Soldermask Top")
		(3 "B.Mask" user "Board Geometry/Soldermask Bottom")
		(17 "Dwgs.User" user "User.Drawings")
		(19 "Cmts.User" user "User.Comments")
		(21 "Eco1.User" user "User.Eco1")
		(23 "Eco2.User" user "User.Eco2")
		(25 "Edge.Cuts" user "Board Geometry/Outline")
		(27 "Margin" user)
		(31 "F.CrtYd" user "Package Geometry/Place Bound Top")
		(29 "B.CrtYd" user "Package Geometry/Place Bound Bottom")
		(35 "F.Fab" user "Ref Des/Assembly Top")
		(33 "B.Fab" user "Ref Des/Assembly Bottom")
	)
	(footprint ""
		(layer "B.Cu")
		(at 325.635112 -34.651442 90)
		(property "Reference" "R3939"
			(at 0 0 90)
			(layer "B.SilkS")
			(hide yes)
			(effects
				(font
					(size 1.27 1.27)
				)
				(justify mirror)
			)
		)
		(property "Value" ""
			(at 0 0 90)
			(layer "B.Fab")
			(effects
				(font
					(size 1.27 1.27)
				)
				(justify mirror)
			)
		)
		(duplicate_pad_numbers_are_jumpers no)
		(fp_line
			(start 0.7874 -0.4064)
			(end -0.7874 -0.4064)
			(stroke
				(width 0.1524)
				(type default)
			)
			(layer "B.SilkS")
		)
		(fp_line
			(start -0.7874 -0.4064)
			(end -0.7874 0.4064)
			(stroke
				(width 0.1524)
				(type default)
			)
			(layer "B.SilkS")
		)
		(fp_line
			(start 0.7874 0.4064)
			(end 0.7874 -0.4064)
			(stroke
				(width 0.1524)
				(type default)
			)
			(layer "B.SilkS")
		)
		(fp_line
			(start -0.7874 0.4064)
			(end 0.7874 0.4064)
			(stroke
				(width 0.1524)
				(type default)
			)
			(layer "B.SilkS")
		)
		(fp_line
			(start 0.67945 -0.305054)
			(end 0.12065 -0.305054)
			(stroke
				(width 0.1)
				(type default)
			)
			(layer "B.Fab")
		)
		(fp_line
			(start 0.12065 -0.305054)
			(end 0.12065 -0.2794)
			(stroke
				(width 0.1)
				(type default)
			)
			(layer "B.Fab")
		)
		(fp_line
			(start -0.12065 -0.3048)
			(end -0.67945 -0.3048)
			(stroke
				(width 0.1)
				(type default)
			)
			(layer "B.Fab")
		)
		(fp_line
			(start -0.67945 -0.3048)
			(end -0.67945 0.3048)
			(stroke
				(width 0.1)
				(type default)
			)
			(layer "B.Fab")
		)
		(fp_line
			(start 0.12065 -0.2794)
			(end -0.12065 -0.2794)
			(stroke
				(width 0.1)
				(type default)
			)
			(layer "B.Fab")
		)
		(fp_line
			(start -0.12065 -0.2794)
			(end -0.12065 -0.3048)
			(stroke
				(width 0.1)
				(type default)
			)
			(layer "B.Fab")
		)
		(fp_line
			(start 0.12065 0.2794)
			(end 0.12065 0.3048)
			(stroke
				(width 0.1)
				(type default)
			)
			(layer "B.Fab")
		)
		(fp_line
			(start -0.120396 0.2794)
			(end 0.12065 0.2794)
			(stroke
				(width 0.1)
				(type default)
			)
			(layer "B.Fab")
		)
		(fp_line
			(start 0.67945 0.3048)
			(end 0.67945 -0.305054)
			(stroke
				(width 0.1)
				(type default)
			)
			(layer "B.Fab")
		)
		(fp_line
			(start 0.12065 0.3048)
			(end 0.67945 0.3048)
			(stroke
				(width 0.1)
				(type default)
			)
			(layer "B.Fab")
		)
		(fp_line
			(start -0.120396 0.3048)
			(end -0.120396 0.2794)
			(stroke
				(width 0.1)
				(type default)
			)
			(layer "B.Fab")
		)
		(fp_line
			(start -0.67945 0.3048)
			(end -0.120396 0.3048)
			(stroke
				(width 0.1)
				(type default)
			)
			(layer "B.Fab")
		)
		(pad "1" smd rect
			(at 0.40005 0 90)
			(size 0.4572 0.508)
			(layers "B.Cu" "B.Mask" "B.Paste")
			(net "P12V_E1S_0_ISENSE_MAM_MAM")
		)
		(pad "2" smd rect
			(at -0.40005 0 90)
			(size 0.4572 0.508)
			(layers "B.Cu" "B.Mask" "B.Paste")
			(net "P12V_E1S_0_ISENSE_MAM")
		)
	)
	(footprint ""
		(layer "B.Cu")
		(at 449.518278 -8.3566 -90)
		(property "Reference" "R34"
			(at 0 0 90)
			(layer "B.SilkS")
			(hide yes)
			(effects
				(font
					(size 1.27 1.27)
				)
				(justify mirror)
			)
		)
		(property "Value" ""
			(at 0 0 90)
			(layer "B.Fab")
			(effects
				(font
					(size 1.27 1.27)
				)
				(justify mirror)
			)
		)
		(duplicate_pad_numbers_are_jumpers no)
		(fp_line
			(start -0.7874 0.4064)
			(end 0.7874 0.4064)
			(stroke
				(width 0.1524)
				(type default)
			)
			(layer "B.SilkS")
		)
		(fp_line
			(start 0.7874 0.4064)
			(end 0.7874 -0.4064)
			(stroke
				(width 0.1524)
				(type default)
			)
			(layer "B.SilkS")
		)
		(fp_line
			(start -0.7874 -0.4064)
			(end -0.7874 0.4064)
			(stroke
				(width 0.1524)
				(type default)
			)
			(layer "B.SilkS")
		)
		(fp_line
			(start 0.7874 -0.4064)
			(end -0.7874 -0.4064)
			(stroke
				(width 0.1524)
				(type default)
			)
			(layer "B.SilkS")
		)
		(fp_line
			(start -0.67945 0.3048)
			(end -0.120396 0.3048)
			(stroke
				(width 0.1)
				(type default)
			)
			(layer "B.Fab")
		)
		(fp_line
			(start -0.120396 0.3048)
			(end -0.120396 0.2794)
			(stroke
				(width 0.1)
				(type default)
			)
			(layer "B.Fab")
		)
		(fp_line
			(start 0.12065 0.3048)
			(end 0.67945 0.3048)
			(stroke
				(width 0.1)
				(type default)
			)
			(layer "B.Fab")
		)
		(fp_line
			(start 0.67945 0.3048)
			(end 0.67945 -0.305054)
			(stroke
				(width 0.1)
				(type default)
			)
			(layer "B.Fab")
		)
		(fp_line
			(start -0.120396 0.2794)
			(end 0.12065 0.2794)
			(stroke
				(width 0.1)
				(type default)
			)
			(layer "B.Fab")
		)
		(fp_line
			(start 0.12065 0.2794)
			(end 0.12065 0.3048)
			(stroke
				(width 0.1)
				(type default)
			)
			(layer "B.Fab")
		)
		(fp_line
			(start -0.12065 -0.2794)
			(end -0.12065 -0.3048)
			(stroke
				(width 0.1)
				(type default)
			)
			(layer "B.Fab")
		)
		(fp_line
			(start 0.12065 -0.2794)
			(end -0.12065 -0.2794)
			(stroke
				(width 0.1)
				(type default)
			)
			(layer "B.Fab")
		)
		(fp_line
			(start -0.67945 -0.3048)
			(end -0.67945 0.3048)
			(stroke
				(width 0.1)
				(type default)
			)
			(layer "B.Fab")
		)
		(fp_line
			(start -0.12065 -0.3048)
			(end -0.67945 -0.3048)
			(stroke
				(width 0.1)
				(type default)
			)
			(layer "B.Fab")
		)
		(fp_line
			(start 0.12065 -0.305054)
			(end 0.12065 -0.2794)
			(stroke
				(width 0.1)
				(type default)
			)
			(layer "B.Fab")
		)
		(fp_line
			(start 0.67945 -0.305054)
			(end 0.12065 -0.305054)
			(stroke
				(width 0.1)
				(type default)
			)
			(layer "B.Fab")
		)
		(pad "1" smd circle
			(at 0.40005 0 90)
			(size 0 0)
			(layers "B.Cu" "B.Mask" "B.Paste")
			(net "OCP_SFF_ID1")
		)
		(pad "2" smd circle
			(at -0.40005 0 90)
			(size 0 0)
			(layers "B.Cu" "B.Mask" "B.Paste")
			(net "GND")
		)
	)
)
